(kicad_pcb
	(version 20260206)
	(generator "pcbnew")
	(generator_version "10.0")
	(general
		(thickness 1.6)
		(legacy_teardrops no)
	)
	(paper "A4")
	(title_block
		(title "03242023_DA0F0TMBIJ0_F0T_Motherboard_J_brd_V01_OCP.brd")
		(comment 1 "Grand Teton / footprints 5878-5884 of 6105")
	)
	(layers
		(0 "F.Cu" signal "TOP")
		(4 "In1.Cu" signal "GND")
		(6 "In2.Cu" signal "IN1")
		(8 "In3.Cu" signal "GND1")
		(10 "In4.Cu" signal "IN2")
		(12 "In5.Cu" signal "GND2")
		(14 "In6.Cu" signal "IN3")
		(16 "In7.Cu" signal "GND3")
		(18 "In8.Cu" signal "VCC")
		(20 "In9.Cu" signal "VCC1")
		(22 "In10.Cu" signal "GND4")
		(24 "In11.Cu" signal "IN4")
		(26 "In12.Cu" signal "GND5")
		(28 "In13.Cu" signal "IN5")
		(30 "In14.Cu" signal "GND6")
		(32 "In15.Cu" signal "IN6")
		(34 "In16.Cu" signal "GND7")
		(2 "B.Cu" signal "BOTTOM")
		(9 "F.Adhes" user "F.Adhesive")
		(11 "B.Adhes" user "B.Adhesive")
		(13 "F.Paste" user "Package Geometry/Pastemask Top")
		(15 "B.Paste" user "Package Geometry/Pastemask Bottom")
		(5 "F.SilkS" user "Ref Des/Silkscreen Top")
		(7 "B.SilkS" user "Ref Des/Silkscreen Bottom")
		(1 "F.Mask" user "Board Geometry/Soldermask Top")
		(3 "B.Mask" user "Board Geometry/Soldermask Bottom")
		(17 "Dwgs.User" user "User.Drawings")
		(19 "Cmts.User" user "User.Comments")
		(21 "Eco1.User" user "User.Eco1")
		(23 "Eco2.User" user "User.Eco2")
		(25 "Edge.Cuts" user "Board Geometry/Outline")
		(27 "Margin" user)
		(31 "F.CrtYd" user "Package Geometry/Place Bound Top")
		(29 "B.CrtYd" user "Package Geometry/Place Bound Bottom")
		(35 "F.Fab" user "Ref Des/Assembly Top")
		(33 "B.Fab" user "Ref Des/Assembly Bottom")
	)
	(footprint ""
		(layer "B.Cu")
		(at 141.057122 -342.936576 90)
		(property "Reference" "PC493_P1_8"
			(at 0 0 90)
			(layer "B.SilkS")
			(hide yes)
			(effects
				(font
					(size 1.27 1.27)
				)
				(justify mirror)
			)
		)
		(property "Value" ""
			(at 0 0 90)
			(layer "B.Fab")
			(effects
				(font
					(size 1.27 1.27)
				)
				(justify mirror)
			)
		)
		(duplicate_pad_numbers_are_jumpers no)
		(fp_line
			(start 1.524 -0.762)
			(end -1.524 -0.762)
			(stroke
				(width 0.1524)
				(type default)
			)
			(layer "B.SilkS")
		)
		(fp_line
			(start -1.524 -0.762)
			(end -1.524 0.762)
			(stroke
				(width 0.1524)
				(type default)
			)
			(layer "B.SilkS")
		)
		(fp_line
			(start 1.524 0.762)
			(end 1.524 -0.762)
			(stroke
				(width 0.1524)
				(type default)
			)
			(layer "B.SilkS")
		)
		(fp_line
			(start -1.524 0.762)
			(end 1.524 0.762)
			(stroke
				(width 0.1524)
				(type default)
			)
			(layer "B.SilkS")
		)
		(fp_line
			(start 1.1049 -0.724916)
			(end 1.1049 0.724916)
			(stroke
				(width 0.1)
				(type default)
			)
			(layer "B.Fab")
		)
		(fp_line
			(start -1.1049 -0.724916)
			(end 1.1049 -0.724916)
			(stroke
				(width 0.1)
				(type default)
			)
			(layer "B.Fab")
		)
		(fp_line
			(start 1.1049 0.724916)
			(end -1.1049 0.724916)
			(stroke
				(width 0.1)
				(type default)
			)
			(layer "B.Fab")
		)
		(fp_line
			(start -1.1049 0.724916)
			(end -1.1049 -0.724916)
			(stroke
				(width 0.1)
				(type default)
			)
			(layer "B.Fab")
		)
		(pad "1" smd rect
			(at 0.889 0 90)
			(size 1.016 1.27)
			(layers "B.Cu" "B.Mask" "B.Paste")
			(net "SW_P12V_PVCCIN_CPU1_FLT")
		)
		(pad "2" smd rect
			(at -0.889 0 90)
			(size 1.016 1.27)
			(layers "B.Cu" "B.Mask" "B.Paste")
			(net "GND")
		)
	)
	(footprint ""
		(layer "B.Cu")
		(at 164.64788 -111.470948)
		(property "Reference" "R1660"
			(at 0 0 0)
			(layer "B.SilkS")
			(hide yes)
			(effects
				(font
					(size 1.27 1.27)
				)
				(justify mirror)
			)
		)
		(property "Value" ""
			(at 0 0 0)
			(layer "B.Fab")
			(effects
				(font
					(size 1.27 1.27)
				)
				(justify mirror)
			)
		)
		(duplicate_pad_numbers_are_jumpers no)
		(fp_line
			(start -0.7874 -0.4064)
			(end -0.7874 0.4064)
			(stroke
				(width 0.1524)
				(type default)
			)
			(layer "B.SilkS")
		)
		(fp_line
			(start -0.7874 0.4064)
			(end 0.7874 0.4064)
			(stroke
				(width 0.1524)
				(type default)
			)
			(layer "B.SilkS")
		)
		(fp_line
			(start 0.7874 -0.4064)
			(end -0.7874 -0.4064)
			(stroke
				(width 0.1524)
				(type default)
			)
			(layer "B.SilkS")
		)
		(fp_line
			(start 0.7874 0.4064)
			(end 0.7874 -0.4064)
			(stroke
				(width 0.1524)
				(type default)
			)
			(layer "B.SilkS")
		)
		(fp_line
			(start -0.67945 -0.3048)
			(end -0.67945 0.3048)
			(stroke
				(width 0.1)
				(type default)
			)
			(layer "B.Fab")
		)
		(fp_line
			(start -0.67945 0.3048)
			(end -0.120396 0.3048)
			(stroke
				(width 0.1)
				(type default)
			)
			(layer "B.Fab")
		)
		(fp_line
			(start -0.12065 -0.3048)
			(end -0.67945 -0.3048)
			(stroke
				(width 0.1)
				(type default)
			)
			(layer "B.Fab")
		)
		(fp_line
			(start -0.12065 -0.2794)
			(end -0.12065 -0.3048)
			(stroke
				(width 0.1)
				(type default)
			)
			(layer "B.Fab")
		)
		(fp_line
			(start -0.120396 0.2794)
			(end 0.12065 0.2794)
			(stroke
				(width 0.1)
				(type default)
			)
			(layer "B.Fab")
		)
		(fp_line
			(start -0.120396 0.3048)
			(end -0.120396 0.2794)
			(stroke
				(width 0.1)
				(type default)
			)
			(layer "B.Fab")
		)
		(fp_line
			(start 0.12065 -0.305054)
			(end 0.12065 -0.2794)
			(stroke
				(width 0.1)
				(type default)
			)
			(layer "B.Fab")
		)
		(fp_line
			(start 0.12065 -0.2794)
			(end -0.12065 -0.2794)
			(stroke
				(width 0.1)
				(type default)
			)
			(layer "B.Fab")
		)
		(fp_line
			(start 0.12065 0.2794)
			(end 0.12065 0.3048)
			(stroke
				(width 0.1)
				(type default)
			)
			(layer "B.Fab")
		)
		(fp_line
			(start 0.12065 0.3048)
			(end 0.67945 0.3048)
			(stroke
				(width 0.1)
				(type default)
			)
			(layer "B.Fab")
		)
		(fp_line
			(start 0.67945 -0.305054)
			(end 0.12065 -0.305054)
			(stroke
				(width 0.1)
				(type default)
			)
			(layer "B.Fab")
		)
		(fp_line
			(start 0.67945 0.3048)
			(end 0.67945 -0.305054)
			(stroke
				(width 0.1)
				(type default)
			)
			(layer "B.Fab")
		)
		(pad "1" smd circle
			(at 0.40005 0 180)
			(size 0 0)
			(layers "B.Cu" "B.Mask" "B.Paste")
			(net "FM_SLP_SUS_RSM_RST_N")
		)
		(pad "2" smd circle
			(at -0.40005 0 180)
			(size 0 0)
			(layers "B.Cu" "B.Mask" "B.Paste")
			(net "P3V3_AUX")
		)
	)
	(footprint ""
		(layer "B.Cu")
		(at 436.971694 -121.730008)
		(property "Reference" "R363"
			(at 0 0 0)
			(layer "B.SilkS")
			(hide yes)
			(effects
				(font
					(size 1.27 1.27)
				)
				(justify mirror)
			)
		)
		(property "Value" ""
			(at 0 0 0)
			(layer "B.Fab")
			(effects
				(font
					(size 1.27 1.27)
				)
				(justify mirror)
			)
		)
		(duplicate_pad_numbers_are_jumpers no)
		(fp_line
			(start -0.7874 -0.4064)
			(end -0.7874 0.4064)
			(stroke
				(width 0.1524)
				(type default)
			)
			(layer "B.SilkS")
		)
		(fp_line
			(start -0.7874 0.4064)
			(end 0.7874 0.4064)
			(stroke
				(width 0.1524)
				(type default)
			)
			(layer "B.SilkS")
		)
		(fp_line
			(start 0.7874 -0.4064)
			(end -0.7874 -0.4064)
			(stroke
				(width 0.1524)
				(type default)
			)
			(layer "B.SilkS")
		)
		(fp_line
			(start 0.7874 0.4064)
			(end 0.7874 -0.4064)
			(stroke
				(width 0.1524)
				(type default)
			)
			(layer "B.SilkS")
		)
		(fp_line
			(start -0.67945 -0.3048)
			(end -0.67945 0.3048)
			(stroke
				(width 0.1)
				(type default)
			)
			(layer "B.Fab")
		)
		(fp_line
			(start -0.67945 0.3048)
			(end -0.120396 0.3048)
			(stroke
				(width 0.1)
				(type default)
			)
			(layer "B.Fab")
		)
		(fp_line
			(start -0.12065 -0.3048)
			(end -0.67945 -0.3048)
			(stroke
				(width 0.1)
				(type default)
			)
			(layer "B.Fab")
		)
		(fp_line
			(start -0.12065 -0.2794)
			(end -0.12065 -0.3048)
			(stroke
				(width 0.1)
				(type default)
			)
			(layer "B.Fab")
		)
		(fp_line
			(start -0.120396 0.2794)
			(end 0.12065 0.2794)
			(stroke
				(width 0.1)
				(type default)
			)
			(layer "B.Fab")
		)
		(fp_line
			(start -0.120396 0.3048)
			(end -0.120396 0.2794)
			(stroke
				(width 0.1)
				(type default)
			)
			(layer "B.Fab")
		)
		(fp_line
			(start 0.12065 -0.305054)
			(end 0.12065 -0.2794)
			(stroke
				(width 0.1)
				(type default)
			)
			(layer "B.Fab")
		)
		(fp_line
			(start 0.12065 -0.2794)
			(end -0.12065 -0.2794)
			(stroke
				(width 0.1)
				(type default)
			)
			(layer "B.Fab")
		)
		(fp_line
			(start 0.12065 0.2794)
			(end 0.12065 0.3048)
			(stroke
				(width 0.1)
				(type default)
			)
			(layer "B.Fab")
		)
		(fp_line
			(start 0.12065 0.3048)
			(end 0.67945 0.3048)
			(stroke
				(width 0.1)
				(type default)
			)
			(layer "B.Fab")
		)
		(fp_line
			(start 0.67945 -0.305054)
			(end 0.12065 -0.305054)
			(stroke
				(width 0.1)
				(type default)
			)
			(layer "B.Fab")
		)
		(fp_line
			(start 0.67945 0.3048)
			(end 0.67945 -0.305054)
			(stroke
				(width 0.1)
				(type default)
			)
			(layer "B.Fab")
		)
		(pad "1" smd circle
			(at 0.40005 0 180)
			(size 0 0)
			(layers "B.Cu" "B.Mask" "B.Paste")
			(net "FM_PVCCD_HV_CPU0_EN")
		)
		(pad "2" smd circle
			(at -0.40005 0 180)
			(size 0 0)
			(layers "B.Cu" "B.Mask" "B.Paste")
			(net "PVCCD_HV_CPU0_EN_R")
		)
	)
	(footprint ""
		(layer "B.Cu")
		(at 429.397414 -321.549776 -90)
		(property "Reference" "C33"
			(at 0 0 90)
			(layer "B.SilkS")
			(hide yes)
			(effects
				(font
					(size 1.27 1.27)
				)
				(justify mirror)
			)
		)
		(property "Value" ""
			(at 0 0 90)
			(layer "B.Fab")
			(effects
				(font
					(size 1.27 1.27)
				)
				(justify mirror)
			)
		)
		(duplicate_pad_numbers_are_jumpers no)
		(fp_line
			(start -1.524 0.762)
			(end 1.524 0.762)
			(stroke
				(width 0.1524)
				(type default)
			)
			(layer "B.SilkS")
		)
		(fp_line
			(start 1.524 0.762)
			(end 1.524 -0.762)
			(stroke
				(width 0.1524)
				(type default)
			)
			(layer "B.SilkS")
		)
		(fp_line
			(start -1.524 -0.762)
			(end -1.524 0.762)
			(stroke
				(width 0.1524)
				(type default)
			)
			(layer "B.SilkS")
		)
		(fp_line
			(start 1.524 -0.762)
			(end -1.524 -0.762)
			(stroke
				(width 0.1524)
				(type default)
			)
			(layer "B.SilkS")
		)
		(fp_line
			(start -1.1049 0.724916)
			(end -1.1049 -0.724916)
			(stroke
				(width 0.1)
				(type default)
			)
			(layer "B.Fab")
		)
		(fp_line
			(start 1.1049 0.724916)
			(end -1.1049 0.724916)
			(stroke
				(width 0.1)
				(type default)
			)
			(layer "B.Fab")
		)
		(fp_line
			(start -1.1049 -0.724916)
			(end 1.1049 -0.724916)
			(stroke
				(width 0.1)
				(type default)
			)
			(layer "B.Fab")
		)
		(fp_line
			(start 1.1049 -0.724916)
			(end 1.1049 0.724916)
			(stroke
				(width 0.1)
				(type default)
			)
			(layer "B.Fab")
		)
		(pad "1" smd rect
			(at 0.889 0 270)
			(size 1.016 1.27)
			(layers "B.Cu" "B.Mask" "B.Paste")
			(net "P12V_S3_AUX_CPU0_NVDIMM")
		)
		(pad "2" smd rect
			(at -0.889 0 270)
			(size 1.016 1.27)
			(layers "B.Cu" "B.Mask" "B.Paste")
			(net "GND")
		)
	)
	(footprint ""
		(layer "B.Cu")
		(at 121.582688 -210.194144 180)
		(property "Reference" "C487"
			(at 0 0 0)
			(layer "B.SilkS")
			(hide yes)
			(effects
				(font
					(size 1.27 1.27)
				)
				(justify mirror)
			)
		)
		(property "Value" ""
			(at 0 0 0)
			(layer "B.Fab")
			(effects
				(font
					(size 1.27 1.27)
				)
				(justify mirror)
			)
		)
		(duplicate_pad_numbers_are_jumpers no)
		(fp_line
			(start 1.524 0.762)
			(end 1.524 -0.762)
			(stroke
				(width 0.1524)
				(type default)
			)
			(layer "B.SilkS")
		)
		(fp_line
			(start 1.524 -0.762)
			(end -1.524 -0.762)
			(stroke
				(width 0.1524)
				(type default)
			)
			(layer "B.SilkS")
		)
		(fp_line
			(start -1.524 0.762)
			(end 1.524 0.762)
			(stroke
				(width 0.1524)
				(type default)
			)
			(layer "B.SilkS")
		)
		(fp_line
			(start -1.524 -0.762)
			(end -1.524 0.762)
			(stroke
				(width 0.1524)
				(type default)
			)
			(layer "B.SilkS")
		)
		(fp_line
			(start 1.1049 0.724916)
			(end -1.1049 0.724916)
			(stroke
				(width 0.1)
				(type default)
			)
			(layer "B.Fab")
		)
		(fp_line
			(start 1.1049 -0.724916)
			(end 1.1049 0.724916)
			(stroke
				(width 0.1)
				(type default)
			)
			(layer "B.Fab")
		)
		(fp_line
			(start -1.1049 0.724916)
			(end -1.1049 -0.724916)
			(stroke
				(width 0.1)
				(type default)
			)
			(layer "B.Fab")
		)
		(fp_line
			(start -1.1049 -0.724916)
			(end 1.1049 -0.724916)
			(stroke
				(width 0.1)
				(type default)
			)
			(layer "B.Fab")
		)
		(pad "1" smd rect
			(at 0.889 0 180)
			(size 1.016 1.27)
			(layers "B.Cu" "B.Mask" "B.Paste")
			(net "PVCCINFAON_CPU1")
		)
		(pad "2" smd rect
			(at -0.889 0 180)
			(size 1.016 1.27)
			(layers "B.Cu" "B.Mask" "B.Paste")
			(net "GND")
		)
	)
	(footprint ""
		(layer "B.Cu")
		(at 435.145942 -8.316976 -90)
		(property "Reference" "R1895"
			(at 0 0 90)
			(layer "B.SilkS")
			(hide yes)
			(effects
				(font
					(size 1.27 1.27)
				)
				(justify mirror)
			)
		)
		(property "Value" ""
			(at 0 0 90)
			(layer "B.Fab")
			(effects
				(font
					(size 1.27 1.27)
				)
				(justify mirror)
			)
		)
		(duplicate_pad_numbers_are_jumpers no)
		(fp_line
			(start -0.7874 0.4064)
			(end 0.7874 0.4064)
			(stroke
				(width 0.1524)
				(type default)
			)
			(layer "B.SilkS")
		)
		(fp_line
			(start 0.7874 0.4064)
			(end 0.7874 -0.4064)
			(stroke
				(width 0.1524)
				(type default)
			)
			(layer "B.SilkS")
		)
		(fp_line
			(start -0.7874 -0.4064)
			(end -0.7874 0.4064)
			(stroke
				(width 0.1524)
				(type default)
			)
			(layer "B.SilkS")
		)
		(fp_line
			(start 0.7874 -0.4064)
			(end -0.7874 -0.4064)
			(stroke
				(width 0.1524)
				(type default)
			)
			(layer "B.SilkS")
		)
		(fp_line
			(start -0.67945 0.3048)
			(end -0.120396 0.3048)
			(stroke
				(width 0.1)
				(type default)
			)
			(layer "B.Fab")
		)
		(fp_line
			(start -0.120396 0.3048)
			(end -0.120396 0.2794)
			(stroke
				(width 0.1)
				(type default)
			)
			(layer "B.Fab")
		)
		(fp_line
			(start 0.12065 0.3048)
			(end 0.67945 0.3048)
			(stroke
				(width 0.1)
				(type default)
			)
			(layer "B.Fab")
		)
		(fp_line
			(start 0.67945 0.3048)
			(end 0.67945 -0.305054)
			(stroke
				(width 0.1)
				(type default)
			)
			(layer "B.Fab")
		)
		(fp_line
			(start -0.120396 0.2794)
			(end 0.12065 0.2794)
			(stroke
				(width 0.1)
				(type default)
			)
			(layer "B.Fab")
		)
		(fp_line
			(start 0.12065 0.2794)
			(end 0.12065 0.3048)
			(stroke
				(width 0.1)
				(type default)
			)
			(layer "B.Fab")
		)
		(fp_line
			(start -0.12065 -0.2794)
			(end -0.12065 -0.3048)
			(stroke
				(width 0.1)
				(type default)
			)
			(layer "B.Fab")
		)
		(fp_line
			(start 0.12065 -0.2794)
			(end -0.12065 -0.2794)
			(stroke
				(width 0.1)
				(type default)
			)
			(layer "B.Fab")
		)
		(fp_line
			(start -0.67945 -0.3048)
			(end -0.67945 0.3048)
			(stroke
				(width 0.1)
				(type default)
			)
			(layer "B.Fab")
		)
		(fp_line
			(start -0.12065 -0.3048)
			(end -0.67945 -0.3048)
			(stroke
				(width 0.1)
				(type default)
			)
			(layer "B.Fab")
		)
		(fp_line
			(start 0.12065 -0.305054)
			(end 0.12065 -0.2794)
			(stroke
				(width 0.1)
				(type default)
			)
			(layer "B.Fab")
		)
		(fp_line
			(start 0.67945 -0.305054)
			(end 0.12065 -0.305054)
			(stroke
				(width 0.1)
				(type default)
			)
			(layer "B.Fab")
		)
		(pad "1" smd circle
			(at 0.40005 0 90)
			(size 0 0)
			(layers "B.Cu" "B.Mask" "B.Paste")
			(net "OCP_SFF_PRSNTA_R_N")
		)
		(pad "2" smd circle
			(at -0.40005 0 90)
			(size 0 0)
			(layers "B.Cu" "B.Mask" "B.Paste")
			(net "GND")
		)
	)
	(footprint ""
		(layer "B.Cu")
		(at 407.0731 -319.080642 90)
		(property "Reference" "C29"
			(at 0 0 90)
			(layer "B.SilkS")
			(hide yes)
			(effects
				(font
					(size 1.27 1.27)
				)
				(justify mirror)
			)
		)
		(property "Value" ""
			(at 0 0 90)
			(layer "B.Fab")
			(effects
				(font
					(size 1.27 1.27)
				)
				(justify mirror)
			)
		)
		(duplicate_pad_numbers_are_jumpers no)
		(fp_line
			(start 0.7874 -0.4064)
			(end -0.7874 -0.4064)
			(stroke
				(width 0.1524)
				(type default)
			)
			(layer "B.SilkS")
		)
		(fp_line
			(start -0.7874 -0.4064)
			(end -0.7874 0.4064)
			(stroke
				(width 0.1524)
				(type default)
			)
			(layer "B.SilkS")
		)
		(fp_line
			(start 0.7874 0.4064)
			(end 0.7874 -0.4064)
			(stroke
				(width 0.1524)
				(type default)
			)
			(layer "B.SilkS")
		)
		(fp_line
			(start -0.7874 0.4064)
			(end 0.7874 0.4064)
			(stroke
				(width 0.1524)
				(type default)
			)
			(layer "B.SilkS")
		)
		(fp_line
			(start 0.67945 -0.305054)
			(end 0.12065 -0.305054)
			(stroke
				(width 0.1)
				(type default)
			)
			(layer "B.Fab")
		)
		(fp_line
			(start 0.12065 -0.305054)
			(end 0.12065 -0.2794)
			(stroke
				(width 0.1)
				(type default)
			)
			(layer "B.Fab")
		)
		(fp_line
			(start -0.12065 -0.3048)
			(end -0.67945 -0.3048)
			(stroke
				(width 0.1)
				(type default)
			)
			(layer "B.Fab")
		)
		(fp_line
			(start -0.67945 -0.3048)
			(end -0.67945 0.3048)
			(stroke
				(width 0.1)
				(type default)
			)
			(layer "B.Fab")
		)
		(fp_line
			(start 0.12065 -0.2794)
			(end -0.12065 -0.2794)
			(stroke
				(width 0.1)
				(type default)
			)
			(layer "B.Fab")
		)
		(fp_line
			(start -0.12065 -0.2794)
			(end -0.12065 -0.3048)
			(stroke
				(width 0.1)
				(type default)
			)
			(layer "B.Fab")
		)
		(fp_line
			(start 0.12065 0.2794)
			(end 0.12065 0.3048)
			(stroke
				(width 0.1)
				(type default)
			)
			(layer "B.Fab")
		)
		(fp_line
			(start -0.120396 0.2794)
			(end 0.12065 0.2794)
			(stroke
				(width 0.1)
				(type default)
			)
			(layer "B.Fab")
		)
		(fp_line
			(start 0.67945 0.3048)
			(end 0.67945 -0.305054)
			(stroke
				(width 0.1)
				(type default)
			)
			(layer "B.Fab")
		)
		(fp_line
			(start 0.12065 0.3048)
			(end 0.67945 0.3048)
			(stroke
				(width 0.1)
				(type default)
			)
			(layer "B.Fab")
		)
		(fp_line
			(start -0.120396 0.3048)
			(end -0.120396 0.2794)
			(stroke
				(width 0.1)
				(type default)
			)
			(layer "B.Fab")
		)
		(fp_line
			(start -0.67945 0.3048)
			(end -0.120396 0.3048)
			(stroke
				(width 0.1)
				(type default)
			)
			(layer "B.Fab")
		)
		(pad "1" smd circle
			(at 0.40005 0 270)
			(size 0 0)
			(layers "B.Cu" "B.Mask" "B.Paste")
			(net "P3V3_AUX")
		)
		(pad "2" smd circle
			(at -0.40005 0 270)
			(size 0 0)
			(layers "B.Cu" "B.Mask" "B.Paste")
			(net "GND")
		)
	)
)
